FILE_TYPE = CONNECTIVITY;
{Allegro Design Entry HDL 17.4-2019 S026 (4007227) 1/17/2022}
"PAGE_NUMBER" = 418;
0"NC";
1"P5E_CPU0_P2_TX_BUF_DN<15:8>";
2"P5E_CPU0_P2_TX_BUF_DN<7:0>";
3"P5E_CPU0_P2_TX_BUF_DP<7:0>";
4"P5E_CPU0_P2_TX_BUF_C_DP<7:0>";
5"P5E_CPU0_P2_TX_BUF_C_DN<7:0>";
6"P5E_CPU0_P2_TX_BUF_C_DN<15:8>";
7"P5E_CPU0_P2_TX_BUF_DN<15:8>";
8"P5E_CPU0_P2_TX_BUF_DP<15:8>";
9"P5E_CPU0_P2_TX_BUF_C_DP<15:8>";
10"P5E_CPU0_P2_TX_BUF_DP<15:8>";
11"P5E_CPU0_P2_TX_BUF_DN<7:0>";
12"P5E_CPU0_P2_TX_BUF_DP<7:0>";
13"P5E_CPU0_P2_TX_BUF_DP<9>";
14"P5E_CPU0_P2_TX_BUF_DN<13>";
15"P5E_CPU0_P2_TX_BUF_DP<12>";
16"P5E_CPU0_P2_TX_BUF_DN<12>";
17"P5E_CPU0_P2_TX_BUF_DP<11>";
18"P5E_CPU0_P2_TX_BUF_DP<13>";
19"P5E_CPU0_P2_TX_BUF_DN<14>";
20"P5E_CPU0_P2_TX_BUF_DP<14>";
21"P5E_CPU0_P2_TX_BUF_DP<2>";
22"P5E_CPU0_P2_TX_BUF_DP<1>";
23"P5E_CPU0_P2_TX_BUF_DN<0>";
24"P5E_CPU0_P2_TX_BUF_DN<3>";
25"P5E_CPU0_P2_TX_BUF_DP<4>";
26"P5E_CPU0_P2_TX_BUF_DP<3>";
27"P5E_CPU0_P2_TX_BUF_DP<10>";
28"P5E_CPU0_P2_TX_BUF_DN<6>";
29"P5E_CPU0_P2_TX_BUF_DP<8>";
30"P5E_CPU0_P2_TX_BUF_DN<10>";
31"P5E_CPU0_P2_TX_BUF_DN<11>";
32"P5E_CPU0_P2_TX_BUF_DN<8>";
33"P5E_CPU0_P2_TX_BUF_DN<15>";
34"P5E_CPU0_P2_TX_BUF_DP<6>";
35"P5E_CPU0_P2_TX_BUF_DP<0>";
36"P5E_CPU0_P2_TX_BUF_DN<1>";
37"P5E_CPU0_P2_TX_BUF_DN<2>";
38"P5E_CPU0_P2_TX_BUF_DP<7>";
39"P5E_CPU0_P2_TX_BUF_DN<7>";
40"P5E_CPU0_P2_TX_BUF_DP<5>";
41"P5E_CPU0_P2_TX_BUF_DN<5>";
42"P5E_CPU0_P2_TX_BUF_DN<4>";
43"P5E_CPU0_P2_TX_BUF_DP<15>";
44"P5E_CPU0_P2_TX_BUF_C_DP<9>";
45"P5E_CPU0_P2_TX_BUF_C_DP<8>";
46"P5E_CPU0_P2_TX_BUF_C_DN<8>";
47"P5E_CPU0_P2_TX_BUF_C_DP<10>";
48"P5E_CPU0_P2_TX_BUF_C_DP<11>";
49"P5E_CPU0_P2_TX_BUF_C_DN<10>";
50"P5E_CPU0_P2_TX_BUF_C_DN<11>";
51"P5E_CPU0_P2_TX_BUF_C_DN<12>";
52"P5E_CPU0_P2_TX_BUF_C_DP<12>";
53"P5E_CPU0_P2_TX_BUF_C_DN<13>";
54"P5E_CPU0_P2_TX_BUF_C_DP<13>";
55"P5E_CPU0_P2_TX_BUF_C_DP<15>";
56"P5E_CPU0_P2_TX_BUF_C_DN<14>";
57"P5E_CPU0_P2_TX_BUF_C_DP<14>";
58"P5E_CPU0_P2_TX_BUF_C_DN<15>";
59"P5E_CPU0_P2_TX_BUF_DP<8>";
60"P5E_CPU0_P2_TX_BUF_DP<9>";
61"P5E_CPU0_P2_TX_BUF_DP<10>";
62"P5E_CPU0_P2_TX_BUF_DN<8>";
63"P5E_CPU0_P2_TX_BUF_DN<9>";
64"P5E_CPU0_P2_TX_BUF_DP<11>";
65"P5E_CPU0_P2_TX_BUF_DP<12>";
66"P5E_CPU0_P2_TX_BUF_DN<10>";
67"P5E_CPU0_P2_TX_BUF_DN<11>";
68"P5E_CPU0_P2_TX_BUF_DN<12>";
69"P5E_CPU0_P2_TX_BUF_DP<13>";
70"P5E_CPU0_P2_TX_BUF_DP<14>";
71"P5E_CPU0_P2_TX_BUF_DP<15>";
72"P5E_CPU0_P2_TX_BUF_DN<13>";
73"P5E_CPU0_P2_TX_BUF_DN<14>";
74"P5E_CPU0_P2_TX_BUF_DN<15>";
75"P5E_CPU0_P2_TX_BUF_C_DN<9>";
76"P5E_CPU0_P2_TX_BUF_C_DN<1>";
77"P5E_CPU0_P2_TX_BUF_C_DP<1>";
78"P5E_CPU0_P2_TX_BUF_C_DP<0>";
79"P5E_CPU0_P2_TX_BUF_C_DN<0>";
80"P5E_CPU0_P2_TX_BUF_C_DN<2>";
81"P5E_CPU0_P2_TX_BUF_C_DP<2>";
82"P5E_CPU0_P2_TX_BUF_DP<0>";
83"P5E_CPU0_P2_TX_BUF_DP<1>";
84"P5E_CPU0_P2_TX_BUF_DP<2>";
85"P5E_CPU0_P2_TX_BUF_DN<1>";
86"P5E_CPU0_P2_TX_BUF_DN<0>";
87"P5E_CPU0_P2_TX_BUF_DN<2>";
88"P5E_CPU0_P2_TX_BUF_C_DP<3>";
89"P5E_CPU0_P2_TX_BUF_C_DN<3>";
90"P5E_CPU0_P2_TX_BUF_C_DP<4>";
91"P5E_CPU0_P2_TX_BUF_C_DN<4>";
92"P5E_CPU0_P2_TX_BUF_C_DP<5>";
93"P5E_CPU0_P2_TX_BUF_C_DN<5>";
94"P5E_CPU0_P2_TX_BUF_C_DP<6>";
95"P5E_CPU0_P2_TX_BUF_C_DN<6>";
96"P5E_CPU0_P2_TX_BUF_C_DN<7>";
97"P5E_CPU0_P2_TX_BUF_C_DP<7>";
98"P5E_CPU0_P2_TX_BUF_DP<3>";
99"P5E_CPU0_P2_TX_BUF_DP<5>";
100"P5E_CPU0_P2_TX_BUF_DP<4>";
101"P5E_CPU0_P2_TX_BUF_DN<3>";
102"P5E_CPU0_P2_TX_BUF_DN<4>";
103"P5E_CPU0_P2_TX_BUF_DP<6>";
104"P5E_CPU0_P2_TX_BUF_DP<7>";
105"P5E_CPU0_P2_TX_BUF_DN<5>";
106"P5E_CPU0_P2_TX_BUF_DN<6>";
107"P5E_CPU0_P2_TX_BUF_DN<7>";
108"P5E_CPU0_P2_TX_BUF_DN<9>";
%"TAP"
"1","(-3250,1500)","2","standard","I10";
;
CDS_LIB"standard"
BODY_TYPE"PLUMBING"
HDL_TAP"TRUE";
"B \NAC \NWC"2;
"S \NAC"
BN"2"87;
%"Q_CAP_DIFFBUS"
"2","(-7125,1775)","2","pure_quanta","I100";
;
LOCATION"C6584"
$SEC"1"
CDS_SEC"1"
VALUE"DIFF BUS_0.22UF"
TOLERANCE"20%"
PACK_TYPE"C0201"
MATERIAL"X6S"
VOLTAGE"6.3V"
PIN_NAMES_ROTATE"TRUE"
CDS_LIB"pure_quanta"
CDS_LMAN_SYM_OUTLINE"-25,50,25,-50"
PART_NUMBER"SP_CH4221MEE01"
LOCATION"C6584";
"2"
$PN"2"63;
"1"
$PN"1"75;
%"Q_CAP_DIFFBUS"
"2","(-7125,1825)","2","pure_quanta","I101";
;
LOCATION"C6583"
$SEC"1"
CDS_SEC"1"
VALUE"DIFF BUS_0.22UF"
TOLERANCE"20%"
PACK_TYPE"C0201"
MATERIAL"X6S"
VOLTAGE"6.3V"
PIN_NAMES_ROTATE"TRUE"
CDS_LIB"pure_quanta"
CDS_LMAN_SYM_OUTLINE"-25,50,25,-50"
PART_NUMBER"SP_CH4221MEE01"
LOCATION"C6583";
"2"
$PN"2"60;
"1"
$PN"1"44;
%"TAP"
"1","(-8100,1975)","2","standard","I102";
;
CDS_LIB"standard"
BODY_TYPE"PLUMBING"
HDL_TAP"TRUE";
"B \NAC \NWC"7;
"S \NAC"
BN"8"62;
%"TAP"
"1","(-7850,2025)","2","standard","I103";
;
CDS_LIB"standard"
BODY_TYPE"PLUMBING"
HDL_TAP"TRUE";
"B \NAC \NWC"8;
"S \NAC"
BN"8"59;
%"Q_CAP_DIFFBUS"
"2","(-7125,2025)","2","pure_quanta","I104";
;
LOCATION"C6581"
$SEC"1"
CDS_SEC"1"
TOLERANCE"20%"
MATERIAL"X6S"
PACK_TYPE"C0201"
VOLTAGE"6.3V"
VALUE"DIFF BUS_0.22UF"
PIN_NAMES_ROTATE"TRUE"
CDS_LMAN_SYM_OUTLINE"-25,50,25,-50"
CDS_LIB"pure_quanta"
PART_NUMBER"SP_CH4221MEE01"
LOCATION"C6581";
"2"
$PN"2"59;
"1"
$PN"1"45;
%"Q_CAP_DIFFBUS"
"2","(-7125,1975)","2","pure_quanta","I105";
;
LOCATION"C6582"
$SEC"1"
CDS_SEC"1"
VALUE"DIFF BUS_0.22UF"
TOLERANCE"20%"
PACK_TYPE"C0201"
MATERIAL"X6S"
VOLTAGE"6.3V"
PIN_NAMES_ROTATE"TRUE"
CDS_LIB"pure_quanta"
CDS_LMAN_SYM_OUTLINE"-25,50,25,-50"
PART_NUMBER"SP_CH4221MEE01"
LOCATION"C6582";
"2"
$PN"2"62;
"1"
$PN"1"46;
%"TAP"
"1","(-6575,625)","0","standard","I106";
;
CDS_LIB"standard"
BODY_TYPE"PLUMBING"
HDL_TAP"TRUE";
"B \NAC \NWC"9;
"S \NAC"
BN"15"55;
%"TAP"
"1","(-6575,825)","0","standard","I107";
;
CDS_LIB"standard"
BODY_TYPE"PLUMBING"
HDL_TAP"TRUE";
"B \NAC \NWC"9;
"S \NAC"
BN"14"57;
%"TAP"
"1","(-6375,575)","0","standard","I108";
;
CDS_LIB"standard"
BODY_TYPE"PLUMBING"
HDL_TAP"TRUE";
"B \NAC \NWC"6;
"S \NAC"
BN"15"58;
%"TAP"
"1","(-6375,775)","0","standard","I109";
;
CDS_LIB"standard"
BODY_TYPE"PLUMBING"
HDL_TAP"TRUE";
"B \NAC \NWC"6;
"S \NAC"
BN"14"56;
%"TAP"
"1","(-3250,1700)","2","standard","I11";
;
CDS_LIB"standard"
BODY_TYPE"PLUMBING"
HDL_TAP"TRUE";
"B \NAC \NWC"2;
"S \NAC"
BN"1"85;
%"TAP"
"1","(-6575,1025)","0","standard","I110";
;
CDS_LIB"standard"
BODY_TYPE"PLUMBING"
HDL_TAP"TRUE";
"B \NAC \NWC"9;
"S \NAC"
BN"13"54;
%"TAP"
"1","(-6575,1225)","0","standard","I111";
;
CDS_LIB"standard"
BODY_TYPE"PLUMBING"
HDL_TAP"TRUE";
"B \NAC \NWC"9;
"S \NAC"
BN"12"52;
%"TAP"
"1","(-6375,975)","0","standard","I112";
;
CDS_LIB"standard"
BODY_TYPE"PLUMBING"
HDL_TAP"TRUE";
"B \NAC \NWC"6;
"S \NAC"
BN"13"53;
%"TAP"
"1","(-6375,1175)","0","standard","I113";
;
CDS_LIB"standard"
BODY_TYPE"PLUMBING"
HDL_TAP"TRUE";
"B \NAC \NWC"6;
"S \NAC"
BN"12"51;
%"TAP"
"1","(-6375,1375)","0","standard","I114";
;
CDS_LIB"standard"
BODY_TYPE"PLUMBING"
HDL_TAP"TRUE";
"B \NAC \NWC"6;
"S \NAC"
BN"11"50;
%"TAP"
"1","(-6575,1425)","0","standard","I115";
;
CDS_LIB"standard"
BODY_TYPE"PLUMBING"
HDL_TAP"TRUE";
"B \NAC \NWC"9;
"S \NAC"
BN"11"48;
%"TAP"
"1","(-6575,1625)","0","standard","I116";
;
CDS_LIB"standard"
BODY_TYPE"PLUMBING"
HDL_TAP"TRUE";
"B \NAC \NWC"9;
"S \NAC"
BN"10"47;
%"TAP"
"1","(-6575,1825)","0","standard","I117";
;
CDS_LIB"standard"
BODY_TYPE"PLUMBING"
HDL_TAP"TRUE";
"B \NAC \NWC"9;
"S \NAC"
BN"9"44;
%"TAP"
"1","(-6375,1575)","0","standard","I118";
;
CDS_LIB"standard"
BODY_TYPE"PLUMBING"
HDL_TAP"TRUE";
"B \NAC \NWC"6;
"S \NAC"
BN"10"49;
%"TAP"
"1","(-6375,1775)","0","standard","I119";
;
CDS_LIB"standard"
BODY_TYPE"PLUMBING"
HDL_TAP"TRUE";
"B \NAC \NWC"6;
"S \NAC"
BN"9"75;
%"TAP"
"1","(-3000,950)","2","standard","I12";
;
CDS_LIB"standard"
BODY_TYPE"PLUMBING"
HDL_TAP"TRUE";
"B \NAC \NWC"3;
"S \NAC"
BN"5"99;
%"TAP"
"1","(-6575,2025)","0","standard","I120";
;
CDS_LIB"standard"
BODY_TYPE"PLUMBING"
HDL_TAP"TRUE";
"B \NAC \NWC"9;
"S \NAC"
BN"8"45;
%"TAP"
"1","(-6375,1975)","0","standard","I121";
;
CDS_LIB"standard"
BODY_TYPE"PLUMBING"
HDL_TAP"TRUE";
"B \NAC \NWC"6;
"S \NAC"
BN"8"46;
%"TAP"
"1","(-1925,3150)","0","standard","I122";
;
CDS_LIB"standard"
BODY_TYPE"PLUMBING"
HDL_TAP"TRUE";
"B \NAC \NWC"12;
"S \NAC"
BN"0"35;
%"TAP"
"1","(-1725,3050)","0","standard","I123";
;
CDS_LIB"standard"
BODY_TYPE"PLUMBING"
HDL_TAP"TRUE";
"B \NAC \NWC"11;
"S \NAC"
BN"0"23;
%"TAP"
"1","(-1925,3500)","0","standard","I124";
;
CDS_LIB"standard"
BODY_TYPE"PLUMBING"
HDL_TAP"TRUE";
"B \NAC \NWC"12;
"S \NAC"
BN"1"22;
%"TAP"
"1","(-1925,3850)","0","standard","I125";
;
CDS_LIB"standard"
BODY_TYPE"PLUMBING"
HDL_TAP"TRUE";
"B \NAC \NWC"12;
"S \NAC"
BN"2"21;
%"TAP"
"1","(-1725,3400)","0","standard","I126";
;
CDS_LIB"standard"
BODY_TYPE"PLUMBING"
HDL_TAP"TRUE";
"B \NAC \NWC"11;
"S \NAC"
BN"1"36;
%"TAP"
"1","(-1725,3750)","0","standard","I127";
;
CDS_LIB"standard"
BODY_TYPE"PLUMBING"
HDL_TAP"TRUE";
"B \NAC \NWC"11;
"S \NAC"
BN"2"37;
%"TAP"
"1","(-3000,1150)","2","standard","I13";
;
CDS_LIB"standard"
BODY_TYPE"PLUMBING"
HDL_TAP"TRUE";
"B \NAC \NWC"3;
"S \NAC"
BN"4"100;
%"TAP"
"1","(-1925,4200)","0","standard","I130";
;
CDS_LIB"standard"
BODY_TYPE"PLUMBING"
HDL_TAP"TRUE";
"B \NAC \NWC"12;
"S \NAC"
BN"3"26;
%"TAP"
"1","(-1725,4100)","0","standard","I131";
;
CDS_LIB"standard"
BODY_TYPE"PLUMBING"
HDL_TAP"TRUE";
"B \NAC \NWC"11;
"S \NAC"
BN"3"24;
%"TAP"
"1","(-1925,4550)","0","standard","I132";
;
CDS_LIB"standard"
BODY_TYPE"PLUMBING"
HDL_TAP"TRUE";
"B \NAC \NWC"12;
"S \NAC"
BN"4"25;
%"TAP"
"1","(-1925,4900)","0","standard","I133";
;
CDS_LIB"standard"
BODY_TYPE"PLUMBING"
HDL_TAP"TRUE";
"B \NAC \NWC"12;
"S \NAC"
BN"5"40;
%"TAP"
"1","(-1725,4450)","0","standard","I134";
;
CDS_LIB"standard"
BODY_TYPE"PLUMBING"
HDL_TAP"TRUE";
"B \NAC \NWC"11;
"S \NAC"
BN"4"42;
%"TAP"
"1","(-1725,4800)","0","standard","I135";
;
CDS_LIB"standard"
BODY_TYPE"PLUMBING"
HDL_TAP"TRUE";
"B \NAC \NWC"11;
"S \NAC"
BN"5"41;
%"TAP"
"1","(-1925,5250)","0","standard","I136";
;
CDS_LIB"standard"
BODY_TYPE"PLUMBING"
HDL_TAP"TRUE";
"B \NAC \NWC"12;
"S \NAC"
BN"6"34;
%"TAP"
"1","(-1725,5150)","0","standard","I137";
;
CDS_LIB"standard"
BODY_TYPE"PLUMBING"
HDL_TAP"TRUE";
"B \NAC \NWC"11;
"S \NAC"
BN"6"28;
%"TAP"
"1","(-1925,5600)","0","standard","I138";
;
CDS_LIB"standard"
BODY_TYPE"PLUMBING"
HDL_TAP"TRUE";
"B \NAC \NWC"12;
"S \NAC"
BN"7"38;
%"TAP"
"1","(-1725,5500)","0","standard","I139";
;
CDS_LIB"standard"
BODY_TYPE"PLUMBING"
HDL_TAP"TRUE";
"B \NAC \NWC"11;
"S \NAC"
BN"7"39;
%"TAP"
"1","(-3000,1350)","2","standard","I14";
;
CDS_LIB"standard"
BODY_TYPE"PLUMBING"
HDL_TAP"TRUE";
"B \NAC \NWC"3;
"S \NAC"
BN"3"98;
%"PT5161LRS"
"11","(-2650,4350)","0","pure_quanta","I142";
;
LOCATION"U6012"
$SEC"11"
CDS_SEC"11"
VALUE"PT5161LRS"
MATERIAL"IC"
PART_TYPE"SMLF"
CDS_LIB"pure_quanta"
CDS_LMAN_SYM_OUTLINE"-350,1450,300,-1400"
NEEDS_NO_SIZE"TRUE"
PART_NUMBER"AJ051610U03";
"B_PETN15"
$PN"EW10"23;
"B_PETP15"
$PN"EU7"35;
"B_PETN14"
$PN"EM10"36;
"B_PETP14"
$PN"EK7"22;
"B_PETN13"
$PN"EE10"37;
"B_PETP13"
$PN"EC7"21;
"B_PETN12"
$PN"DV10"24;
"B_PETP12"
$PN"DT7"26;
"B_PETN11"
$PN"DL10"42;
"B_PETP11"
$PN"DJ7"25;
"B_PETN10"
$PN"DD10"41;
"B_PETP10"
$PN"DB7"40;
"B_PETN9"
$PN"CU10"28;
"B_PETP9"
$PN"CR7"34;
"B_PETN8"
$PN"CK10"39;
"B_PETP8"
$PN"CH7"38;
%"TAP"
"1","(-3000,1750)","2","standard","I15";
;
CDS_LIB"standard"
BODY_TYPE"PLUMBING"
HDL_TAP"TRUE";
"B \NAC \NWC"3;
"S \NAC"
BN"1"83;
%"TAP"
"1","(-3000,1550)","2","standard","I16";
;
CDS_LIB"standard"
BODY_TYPE"PLUMBING"
HDL_TAP"TRUE";
"B \NAC \NWC"3;
"S \NAC"
BN"2"84;
%"Q_CAP_DIFFBUS"
"2","(-2275,500)","2","pure_quanta","I17";
;
LOCATION"C6580"
$SEC"1"
CDS_SEC"1"
VALUE"DIFF BUS_0.22UF"
CDS_LMAN_SYM_OUTLINE"-25,50,25,-50"
CDS_LIB"pure_quanta"
PIN_NAMES_ROTATE"TRUE"
VOLTAGE"6.3V"
MATERIAL"X6S"
PACK_TYPE"C0201"
TOLERANCE"20%"
PART_NUMBER"SP_CH4221MEE01"
LOCATION"C6580";
"2"
$PN"2"107;
"1"
$PN"1"96;
%"Q_CAP_DIFFBUS"
"2","(-2275,550)","2","pure_quanta","I18";
;
LOCATION"C6579"
$SEC"1"
CDS_SEC"1"
VALUE"DIFF BUS_0.22UF"
CDS_LMAN_SYM_OUTLINE"-25,50,25,-50"
CDS_LIB"pure_quanta"
PIN_NAMES_ROTATE"TRUE"
VOLTAGE"6.3V"
MATERIAL"X6S"
PACK_TYPE"C0201"
TOLERANCE"20%"
PART_NUMBER"SP_CH4221MEE01"
LOCATION"C6579";
"2"
$PN"2"104;
"1"
$PN"1"97;
%"Q_CAP_DIFFBUS"
"2","(-2275,750)","2","pure_quanta","I19";
;
LOCATION"C6577"
$SEC"1"
CDS_SEC"1"
VALUE"DIFF BUS_0.22UF"
CDS_LIB"pure_quanta"
CDS_LMAN_SYM_OUTLINE"-25,50,25,-50"
PIN_NAMES_ROTATE"TRUE"
VOLTAGE"6.3V"
MATERIAL"X6S"
PACK_TYPE"C0201"
TOLERANCE"20%"
PART_NUMBER"SP_CH4221MEE01"
LOCATION"C6577";
"2"
$PN"2"103;
"1"
$PN"1"94;
%"Q_CAP_DIFFBUS"
"2","(-2275,700)","2","pure_quanta","I20";
;
LOCATION"C6578"
$SEC"1"
CDS_SEC"1"
VALUE"DIFF BUS_0.22UF"
CDS_LMAN_SYM_OUTLINE"-25,50,25,-50"
CDS_LIB"pure_quanta"
PIN_NAMES_ROTATE"TRUE"
VOLTAGE"6.3V"
MATERIAL"X6S"
PACK_TYPE"C0201"
TOLERANCE"20%"
PART_NUMBER"SP_CH4221MEE01"
LOCATION"C6578";
"2"
$PN"2"106;
"1"
$PN"1"95;
%"TAP"
"1","(-1525,500)","0","standard","I21";
;
CDS_LIB"standard"
BODY_TYPE"PLUMBING"
HDL_TAP"TRUE";
"B \NAC \NWC"5;
"S \NAC"
BN"7"96;
%"TAP"
"1","(-1725,550)","0","standard","I22";
;
CDS_LIB"standard"
BODY_TYPE"PLUMBING"
HDL_TAP"TRUE";
"B \NAC \NWC"4;
"S \NAC"
BN"7"97;
%"TAP"
"1","(-1725,750)","0","standard","I23";
;
CDS_LIB"standard"
BODY_TYPE"PLUMBING"
HDL_TAP"TRUE";
"B \NAC \NWC"4;
"S \NAC"
BN"6"94;
%"TAP"
"1","(-1525,700)","0","standard","I24";
;
CDS_LIB"standard"
BODY_TYPE"PLUMBING"
HDL_TAP"TRUE";
"B \NAC \NWC"5;
"S \NAC"
BN"6"95;
%"Q_CAP_DIFFBUS"
"2","(-2275,950)","2","pure_quanta","I25";
;
LOCATION"C6575"
$SEC"1"
CDS_SEC"1"
VALUE"DIFF BUS_0.22UF"
CDS_LMAN_SYM_OUTLINE"-25,50,25,-50"
CDS_LIB"pure_quanta"
PIN_NAMES_ROTATE"TRUE"
VOLTAGE"6.3V"
MATERIAL"X6S"
PACK_TYPE"C0201"
TOLERANCE"20%"
PART_NUMBER"SP_CH4221MEE01"
LOCATION"C6575";
"2"
$PN"2"99;
"1"
$PN"1"92;
%"Q_CAP_DIFFBUS"
"2","(-2275,900)","2","pure_quanta","I26";
;
LOCATION"C6576"
$SEC"1"
CDS_SEC"1"
VALUE"DIFF BUS_0.22UF"
CDS_LMAN_SYM_OUTLINE"-25,50,25,-50"
CDS_LIB"pure_quanta"
PIN_NAMES_ROTATE"TRUE"
VOLTAGE"6.3V"
MATERIAL"X6S"
PACK_TYPE"C0201"
TOLERANCE"20%"
PART_NUMBER"SP_CH4221MEE01"
LOCATION"C6576";
"2"
$PN"2"105;
"1"
$PN"1"93;
%"Q_CAP_DIFFBUS"
"2","(-2275,1150)","2","pure_quanta","I27";
;
LOCATION"C6573"
$SEC"1"
CDS_SEC"1"
VALUE"DIFF BUS_0.22UF"
CDS_LIB"pure_quanta"
CDS_LMAN_SYM_OUTLINE"-25,50,25,-50"
PIN_NAMES_ROTATE"TRUE"
VOLTAGE"6.3V"
MATERIAL"X6S"
PACK_TYPE"C0201"
TOLERANCE"20%"
PART_NUMBER"SP_CH4221MEE01"
LOCATION"C6573";
"2"
$PN"2"100;
"1"
$PN"1"90;
%"Q_CAP_DIFFBUS"
"2","(-2275,1100)","2","pure_quanta","I28";
;
LOCATION"C6574"
$SEC"1"
CDS_SEC"1"
VALUE"DIFF BUS_0.22UF"
CDS_LIB"pure_quanta"
CDS_LMAN_SYM_OUTLINE"-25,50,25,-50"
PIN_NAMES_ROTATE"TRUE"
VOLTAGE"6.3V"
MATERIAL"X6S"
PACK_TYPE"C0201"
TOLERANCE"20%"
PART_NUMBER"SP_CH4221MEE01"
LOCATION"C6574";
"2"
$PN"2"102;
"1"
$PN"1"91;
%"Q_CAP_DIFFBUS"
"2","(-2275,1300)","2","pure_quanta","I29";
;
LOCATION"C6572"
$SEC"1"
CDS_SEC"1"
VALUE"DIFF BUS_0.22UF"
CDS_LMAN_SYM_OUTLINE"-25,50,25,-50"
CDS_LIB"pure_quanta"
PIN_NAMES_ROTATE"TRUE"
VOLTAGE"6.3V"
MATERIAL"X6S"
PACK_TYPE"C0201"
TOLERANCE"20%"
PART_NUMBER"SP_CH4221MEE01"
LOCATION"C6572";
"2"
$PN"2"101;
"1"
$PN"1"89;
%"TAP"
"1","(-3250,500)","2","standard","I3";
;
CDS_LIB"standard"
BODY_TYPE"PLUMBING"
HDL_TAP"TRUE";
"B \NAC \NWC"2;
"S \NAC"
BN"7"107;
%"Q_CAP_DIFFBUS"
"2","(-2275,1350)","2","pure_quanta","I30";
;
LOCATION"C6571"
$SEC"1"
CDS_SEC"1"
VALUE"DIFF BUS_0.22UF"
CDS_LMAN_SYM_OUTLINE"-25,50,25,-50"
CDS_LIB"pure_quanta"
PIN_NAMES_ROTATE"TRUE"
VOLTAGE"6.3V"
MATERIAL"X6S"
PACK_TYPE"C0201"
TOLERANCE"20%"
PART_NUMBER"SP_CH4221MEE01"
LOCATION"C6571";
"2"
$PN"2"98;
"1"
$PN"1"88;
%"Q_CAP_DIFFBUS"
"2","(-2275,1500)","2","pure_quanta","I31";
;
LOCATION"C6570"
$SEC"1"
CDS_SEC"1"
VALUE"DIFF BUS_0.22UF"
CDS_LMAN_SYM_OUTLINE"-25,50,25,-50"
CDS_LIB"pure_quanta"
PIN_NAMES_ROTATE"TRUE"
VOLTAGE"6.3V"
MATERIAL"X6S"
PACK_TYPE"C0201"
TOLERANCE"20%"
PART_NUMBER"SP_CH4221MEE01"
LOCATION"C6570";
"2"
$PN"2"87;
"1"
$PN"1"80;
%"Q_CAP_DIFFBUS"
"2","(-2275,1750)","2","pure_quanta","I32";
;
LOCATION"C6567"
$SEC"1"
CDS_SEC"1"
VALUE"DIFF BUS_0.22UF"
TOLERANCE"20%"
PACK_TYPE"C0201"
MATERIAL"X6S"
VOLTAGE"6.3V"
PIN_NAMES_ROTATE"TRUE"
CDS_LIB"pure_quanta"
CDS_LMAN_SYM_OUTLINE"-25,50,25,-50"
PART_NUMBER"SP_CH4221MEE01"
LOCATION"C6567";
"2"
$PN"2"83;
"1"
$PN"1"77;
%"Q_CAP_DIFFBUS"
"2","(-2275,1700)","2","pure_quanta","I33";
;
LOCATION"C6568"
$SEC"1"
CDS_SEC"1"
VALUE"DIFF BUS_0.22UF"
CDS_LMAN_SYM_OUTLINE"-25,50,25,-50"
CDS_LIB"pure_quanta"
PIN_NAMES_ROTATE"TRUE"
VOLTAGE"6.3V"
MATERIAL"X6S"
PACK_TYPE"C0201"
TOLERANCE"20%"
PART_NUMBER"SP_CH4221MEE01"
LOCATION"C6568";
"2"
$PN"2"85;
"1"
$PN"1"76;
%"Q_CAP_DIFFBUS"
"2","(-2275,1550)","2","pure_quanta","I34";
;
LOCATION"C6569"
$SEC"1"
CDS_SEC"1"
VALUE"DIFF BUS_0.22UF"
CDS_LMAN_SYM_OUTLINE"-25,50,25,-50"
CDS_LIB"pure_quanta"
PIN_NAMES_ROTATE"TRUE"
VOLTAGE"6.3V"
MATERIAL"X6S"
PACK_TYPE"C0201"
TOLERANCE"20%"
PART_NUMBER"SP_CH4221MEE01"
LOCATION"C6569";
"2"
$PN"2"84;
"1"
$PN"1"81;
%"TAP"
"1","(-1725,950)","0","standard","I35";
;
CDS_LIB"standard"
BODY_TYPE"PLUMBING"
HDL_TAP"TRUE";
"B \NAC \NWC"4;
"S \NAC"
BN"5"92;
%"TAP"
"1","(-1525,900)","0","standard","I36";
;
CDS_LIB"standard"
BODY_TYPE"PLUMBING"
HDL_TAP"TRUE";
"B \NAC \NWC"5;
"S \NAC"
BN"5"93;
%"TAP"
"1","(-1725,1150)","0","standard","I37";
;
CDS_LIB"standard"
BODY_TYPE"PLUMBING"
HDL_TAP"TRUE";
"B \NAC \NWC"4;
"S \NAC"
BN"4"90;
%"TAP"
"1","(-1525,1100)","0","standard","I38";
;
CDS_LIB"standard"
BODY_TYPE"PLUMBING"
HDL_TAP"TRUE";
"B \NAC \NWC"5;
"S \NAC"
BN"4"91;
%"TAP"
"1","(-1725,1350)","0","standard","I39";
;
CDS_LIB"standard"
BODY_TYPE"PLUMBING"
HDL_TAP"TRUE";
"B \NAC \NWC"4;
"S \NAC"
BN"3"88;
%"TAP"
"1","(-3250,700)","2","standard","I4";
;
CDS_LIB"standard"
BODY_TYPE"PLUMBING"
HDL_TAP"TRUE";
"B \NAC \NWC"2;
"S \NAC"
BN"6"106;
%"TAP"
"1","(-1525,1500)","0","standard","I40";
;
CDS_LIB"standard"
BODY_TYPE"PLUMBING"
HDL_TAP"TRUE";
"B \NAC \NWC"5;
"S \NAC"
BN"2"80;
%"TAP"
"1","(-1525,1300)","0","standard","I41";
;
CDS_LIB"standard"
BODY_TYPE"PLUMBING"
HDL_TAP"TRUE";
"B \NAC \NWC"5;
"S \NAC"
BN"3"89;
%"TAP"
"1","(-1725,1550)","0","standard","I42";
;
CDS_LIB"standard"
BODY_TYPE"PLUMBING"
HDL_TAP"TRUE";
"B \NAC \NWC"4;
"S \NAC"
BN"2"81;
%"TAP"
"1","(-1725,1750)","0","standard","I43";
;
CDS_LIB"standard"
BODY_TYPE"PLUMBING"
HDL_TAP"TRUE";
"B \NAC \NWC"4;
"S \NAC"
BN"1"77;
%"TAP"
"1","(-1525,1700)","0","standard","I44";
;
CDS_LIB"standard"
BODY_TYPE"PLUMBING"
HDL_TAP"TRUE";
"B \NAC \NWC"5;
"S \NAC"
BN"1"76;
%"TAP"
"1","(-3250,1900)","2","standard","I45";
;
CDS_LIB"standard"
BODY_TYPE"PLUMBING"
HDL_TAP"TRUE";
"B \NAC \NWC"2;
"S \NAC"
BN"0"86;
%"TAP"
"1","(-3000,1950)","2","standard","I46";
;
CDS_LIB"standard"
BODY_TYPE"PLUMBING"
HDL_TAP"TRUE";
"B \NAC \NWC"3;
"S \NAC"
BN"0"82;
%"PT5161LRS"
"10","(-7825,4375)","0","pure_quanta","I47";
;
LOCATION"U6012"
$SEC"10"
CDS_SEC"10"
MATERIAL"IC"
PART_TYPE"SMLF"
VALUE"PT5161LRS"
NEEDS_NO_SIZE"TRUE"
CDS_LMAN_SYM_OUTLINE"-350,1450,300,-1400"
CDS_LIB"pure_quanta"
PART_NUMBER"AJ051610U03";
"B_PETN7"
$PN"CC10"32;
"B_PETP7"
$PN"CA7"29;
"B_PETN6"
$PN"BT10"108;
"B_PETP6"
$PN"BP7"13;
"B_PETN5"
$PN"BJ10"30;
"B_PETP5"
$PN"BG7"27;
"B_PETN4"
$PN"BB10"31;
"B_PETP4"
$PN"AY7"17;
"B_PETN3"
$PN"AR10"16;
"B_PETP3"
$PN"AN7"15;
"B_PETN2"
$PN"AH10"14;
"B_PETP2"
$PN"AF7"18;
"B_PETN1"
$PN"AA10"19;
"B_PETP1"
$PN"W7"20;
"B_PETN0"
$PN"P10"33;
"B_PETP0"
$PN"M7"43;
%"Q_CAP_DIFFBUS"
"2","(-2275,1900)","2","pure_quanta","I48";
;
LOCATION"C6566"
$SEC"1"
CDS_SEC"1"
VALUE"DIFF BUS_0.22UF"
CDS_LMAN_SYM_OUTLINE"-25,50,25,-50"
CDS_LIB"pure_quanta"
PIN_NAMES_ROTATE"TRUE"
VOLTAGE"6.3V"
MATERIAL"X6S"
PACK_TYPE"C0201"
TOLERANCE"20%"
PART_NUMBER"SP_CH4221MEE01"
LOCATION"C6566";
"2"
$PN"2"86;
"1"
$PN"1"79;
%"Q_CAP_DIFFBUS"
"2","(-2275,1950)","2","pure_quanta","I49";
;
LOCATION"C6565"
$SEC"1"
CDS_SEC"1"
PACK_TYPE"C0201"
MATERIAL"X6S"
TOLERANCE"20%"
VOLTAGE"6.3V"
VALUE"DIFF BUS_0.22UF"
CDS_LIB"pure_quanta"
CDS_LMAN_SYM_OUTLINE"-25,50,25,-50"
PIN_NAMES_ROTATE"TRUE"
PART_NUMBER"SP_CH4221MEE01"
LOCATION"C6565";
"2"
$PN"2"82;
"1"
$PN"1"78;
%"TAP"
"1","(-3000,750)","2","standard","I5";
;
CDS_LIB"standard"
BODY_TYPE"PLUMBING"
HDL_TAP"TRUE";
"B \NAC \NWC"3;
"S \NAC"
BN"6"103;
%"TAP"
"1","(-1725,1950)","0","standard","I50";
;
CDS_LIB"standard"
BODY_TYPE"PLUMBING"
HDL_TAP"TRUE";
"B \NAC \NWC"4;
"S \NAC"
BN"0"78;
%"TAP"
"1","(-1525,1900)","0","standard","I51";
;
CDS_LIB"standard"
BODY_TYPE"PLUMBING"
HDL_TAP"TRUE";
"B \NAC \NWC"5;
"S \NAC"
BN"0"79;
%"TAP"
"1","(-7100,3175)","0","standard","I52";
;
CDS_LIB"standard"
BODY_TYPE"PLUMBING"
HDL_TAP"TRUE";
"B \NAC \NWC"10;
"S \NAC"
BN"8"29;
%"TAP"
"1","(-6900,3075)","0","standard","I53";
;
CDS_LIB"standard"
BODY_TYPE"PLUMBING"
HDL_TAP"TRUE";
"B \NAC \NWC"1;
"S \NAC"
BN"8"32;
%"TAP"
"1","(-7100,3525)","0","standard","I54";
;
CDS_LIB"standard"
BODY_TYPE"PLUMBING"
HDL_TAP"TRUE";
"B \NAC \NWC"10;
"S \NAC"
BN"9"13;
%"TAP"
"1","(-7100,3875)","0","standard","I55";
;
CDS_LIB"standard"
BODY_TYPE"PLUMBING"
HDL_TAP"TRUE";
"B \NAC \NWC"10;
"S \NAC"
BN"10"27;
%"TAP"
"1","(-6900,3425)","0","standard","I56";
;
CDS_LIB"standard"
BODY_TYPE"PLUMBING"
HDL_TAP"TRUE";
"B \NAC \NWC"1;
"S \NAC"
BN"9"108;
%"TAP"
"1","(-6900,3775)","0","standard","I57";
;
CDS_LIB"standard"
BODY_TYPE"PLUMBING"
HDL_TAP"TRUE";
"B \NAC \NWC"1;
"S \NAC"
BN"10"30;
%"TAP"
"1","(-3000,550)","2","standard","I6";
;
CDS_LIB"standard"
BODY_TYPE"PLUMBING"
HDL_TAP"TRUE";
"B \NAC \NWC"3;
"S \NAC"
BN"7"104;
%"TAP"
"1","(-7100,4225)","0","standard","I62";
;
CDS_LIB"standard"
BODY_TYPE"PLUMBING"
HDL_TAP"TRUE";
"B \NAC \NWC"10;
"S \NAC"
BN"11"17;
%"TAP"
"1","(-6900,4125)","0","standard","I63";
;
CDS_LIB"standard"
BODY_TYPE"PLUMBING"
HDL_TAP"TRUE";
"B \NAC \NWC"1;
"S \NAC"
BN"11"31;
%"TAP"
"1","(-7100,4575)","0","standard","I64";
;
CDS_LIB"standard"
BODY_TYPE"PLUMBING"
HDL_TAP"TRUE";
"B \NAC \NWC"10;
"S \NAC"
BN"12"15;
%"TAP"
"1","(-6900,4475)","0","standard","I65";
;
CDS_LIB"standard"
BODY_TYPE"PLUMBING"
HDL_TAP"TRUE";
"B \NAC \NWC"1;
"S \NAC"
BN"12"16;
%"TAP"
"1","(-6900,4825)","0","standard","I66";
;
CDS_LIB"standard"
BODY_TYPE"PLUMBING"
HDL_TAP"TRUE";
"B \NAC \NWC"1;
"S \NAC"
BN"13"14;
%"TAP"
"1","(-7100,4925)","0","standard","I67";
;
CDS_LIB"standard"
BODY_TYPE"PLUMBING"
HDL_TAP"TRUE";
"B \NAC \NWC"10;
"S \NAC"
BN"13"18;
%"TAP"
"1","(-7100,5275)","0","standard","I68";
;
CDS_LIB"standard"
BODY_TYPE"PLUMBING"
HDL_TAP"TRUE";
"B \NAC \NWC"10;
"S \NAC"
BN"14"20;
%"TAP"
"1","(-6900,5175)","0","standard","I69";
;
CDS_LIB"standard"
BODY_TYPE"PLUMBING"
HDL_TAP"TRUE";
"B \NAC \NWC"1;
"S \NAC"
BN"14"19;
%"TAP"
"1","(-3250,900)","2","standard","I7";
;
CDS_LIB"standard"
BODY_TYPE"PLUMBING"
HDL_TAP"TRUE";
"B \NAC \NWC"2;
"S \NAC"
BN"5"105;
%"TAP"
"1","(-7100,5625)","0","standard","I70";
;
CDS_LIB"standard"
BODY_TYPE"PLUMBING"
HDL_TAP"TRUE";
"B \NAC \NWC"10;
"S \NAC"
BN"15"43;
%"TAP"
"1","(-6900,5525)","0","standard","I71";
;
CDS_LIB"standard"
BODY_TYPE"PLUMBING"
HDL_TAP"TRUE";
"B \NAC \NWC"1;
"S \NAC"
BN"15"33;
%"TAP"
"1","(-8100,575)","2","standard","I74";
;
CDS_LIB"standard"
BODY_TYPE"PLUMBING"
HDL_TAP"TRUE";
"B \NAC \NWC"7;
"S \NAC"
BN"15"74;
%"TAP"
"1","(-8100,775)","2","standard","I75";
;
CDS_LIB"standard"
BODY_TYPE"PLUMBING"
HDL_TAP"TRUE";
"B \NAC \NWC"7;
"S \NAC"
BN"14"73;
%"TAP"
"1","(-7850,625)","2","standard","I76";
;
CDS_LIB"standard"
BODY_TYPE"PLUMBING"
HDL_TAP"TRUE";
"B \NAC \NWC"8;
"S \NAC"
BN"15"71;
%"TAP"
"1","(-7850,825)","2","standard","I77";
;
CDS_LIB"standard"
BODY_TYPE"PLUMBING"
HDL_TAP"TRUE";
"B \NAC \NWC"8;
"S \NAC"
BN"14"70;
%"TAP"
"1","(-8100,1375)","2","standard","I78";
;
CDS_LIB"standard"
BODY_TYPE"PLUMBING"
HDL_TAP"TRUE";
"B \NAC \NWC"7;
"S \NAC"
BN"11"67;
%"TAP"
"1","(-8100,1175)","2","standard","I79";
;
CDS_LIB"standard"
BODY_TYPE"PLUMBING"
HDL_TAP"TRUE";
"B \NAC \NWC"7;
"S \NAC"
BN"12"68;
%"TAP"
"1","(-3250,1100)","2","standard","I8";
;
CDS_LIB"standard"
BODY_TYPE"PLUMBING"
HDL_TAP"TRUE";
"B \NAC \NWC"2;
"S \NAC"
BN"4"102;
%"TAP"
"1","(-8100,975)","2","standard","I80";
;
CDS_LIB"standard"
BODY_TYPE"PLUMBING"
HDL_TAP"TRUE";
"B \NAC \NWC"7;
"S \NAC"
BN"13"72;
%"TAP"
"1","(-7850,1025)","2","standard","I81";
;
CDS_LIB"standard"
BODY_TYPE"PLUMBING"
HDL_TAP"TRUE";
"B \NAC \NWC"8;
"S \NAC"
BN"13"69;
%"TAP"
"1","(-7850,1225)","2","standard","I82";
;
CDS_LIB"standard"
BODY_TYPE"PLUMBING"
HDL_TAP"TRUE";
"B \NAC \NWC"8;
"S \NAC"
BN"12"65;
%"TAP"
"1","(-8100,1775)","2","standard","I83";
;
CDS_LIB"standard"
BODY_TYPE"PLUMBING"
HDL_TAP"TRUE";
"B \NAC \NWC"7;
"S \NAC"
BN"9"63;
%"TAP"
"1","(-8100,1575)","2","standard","I84";
;
CDS_LIB"standard"
BODY_TYPE"PLUMBING"
HDL_TAP"TRUE";
"B \NAC \NWC"7;
"S \NAC"
BN"10"66;
%"TAP"
"1","(-7850,1425)","2","standard","I85";
;
CDS_LIB"standard"
BODY_TYPE"PLUMBING"
HDL_TAP"TRUE";
"B \NAC \NWC"8;
"S \NAC"
BN"11"64;
%"TAP"
"1","(-7850,1625)","2","standard","I86";
;
CDS_LIB"standard"
BODY_TYPE"PLUMBING"
HDL_TAP"TRUE";
"B \NAC \NWC"8;
"S \NAC"
BN"10"61;
%"TAP"
"1","(-7850,1825)","2","standard","I87";
;
CDS_LIB"standard"
BODY_TYPE"PLUMBING"
HDL_TAP"TRUE";
"B \NAC \NWC"8;
"S \NAC"
BN"9"60;
%"Q_CAP_DIFFBUS"
"2","(-7125,575)","2","pure_quanta","I88";
;
LOCATION"C6596"
$SEC"1"
CDS_SEC"1"
VALUE"DIFF BUS_0.22UF"
TOLERANCE"20%"
PACK_TYPE"C0201"
MATERIAL"X6S"
VOLTAGE"6.3V"
PIN_NAMES_ROTATE"TRUE"
CDS_LIB"pure_quanta"
CDS_LMAN_SYM_OUTLINE"-25,50,25,-50"
PART_NUMBER"SP_CH4221MEE01"
LOCATION"C6596";
"2"
$PN"2"74;
"1"
$PN"1"58;
%"Q_CAP_DIFFBUS"
"2","(-7125,625)","2","pure_quanta","I89";
;
LOCATION"C6595"
$SEC"1"
CDS_SEC"1"
VALUE"DIFF BUS_0.22UF"
TOLERANCE"20%"
PACK_TYPE"C0201"
MATERIAL"X6S"
VOLTAGE"6.3V"
PIN_NAMES_ROTATE"TRUE"
CDS_LIB"pure_quanta"
CDS_LMAN_SYM_OUTLINE"-25,50,25,-50"
PART_NUMBER"SP_CH4221MEE01"
LOCATION"C6595";
"2"
$PN"2"71;
"1"
$PN"1"55;
%"TAP"
"1","(-3250,1300)","2","standard","I9";
;
CDS_LIB"standard"
BODY_TYPE"PLUMBING"
HDL_TAP"TRUE";
"B \NAC \NWC"2;
"S \NAC"
BN"3"101;
%"Q_CAP_DIFFBUS"
"2","(-7125,775)","2","pure_quanta","I90";
;
LOCATION"C6594"
$SEC"1"
CDS_SEC"1"
VALUE"DIFF BUS_0.22UF"
TOLERANCE"20%"
PACK_TYPE"C0201"
MATERIAL"X6S"
VOLTAGE"6.3V"
PIN_NAMES_ROTATE"TRUE"
CDS_LIB"pure_quanta"
CDS_LMAN_SYM_OUTLINE"-25,50,25,-50"
PART_NUMBER"SP_CH4221MEE01"
LOCATION"C6594";
"2"
$PN"2"73;
"1"
$PN"1"56;
%"Q_CAP_DIFFBUS"
"2","(-7125,825)","2","pure_quanta","I91";
;
LOCATION"C6593"
$SEC"1"
CDS_SEC"1"
VALUE"DIFF BUS_0.22UF"
TOLERANCE"20%"
PACK_TYPE"C0201"
MATERIAL"X6S"
VOLTAGE"6.3V"
PIN_NAMES_ROTATE"TRUE"
CDS_LMAN_SYM_OUTLINE"-25,50,25,-50"
CDS_LIB"pure_quanta"
PART_NUMBER"SP_CH4221MEE01"
LOCATION"C6593";
"2"
$PN"2"70;
"1"
$PN"1"57;
%"Q_CAP_DIFFBUS"
"2","(-7125,975)","2","pure_quanta","I92";
;
LOCATION"C6592"
$SEC"1"
CDS_SEC"1"
VALUE"DIFF BUS_0.22UF"
TOLERANCE"20%"
PACK_TYPE"C0201"
MATERIAL"X6S"
VOLTAGE"6.3V"
PIN_NAMES_ROTATE"TRUE"
CDS_LIB"pure_quanta"
CDS_LMAN_SYM_OUTLINE"-25,50,25,-50"
PART_NUMBER"SP_CH4221MEE01"
LOCATION"C6592";
"2"
$PN"2"72;
"1"
$PN"1"53;
%"Q_CAP_DIFFBUS"
"2","(-7125,1025)","2","pure_quanta","I93";
;
LOCATION"C6591"
$SEC"1"
CDS_SEC"1"
VALUE"DIFF BUS_0.22UF"
TOLERANCE"20%"
PACK_TYPE"C0201"
MATERIAL"X6S"
VOLTAGE"6.3V"
PIN_NAMES_ROTATE"TRUE"
CDS_LIB"pure_quanta"
CDS_LMAN_SYM_OUTLINE"-25,50,25,-50"
PART_NUMBER"SP_CH4221MEE01"
LOCATION"C6591";
"2"
$PN"2"69;
"1"
$PN"1"54;
%"Q_CAP_DIFFBUS"
"2","(-7125,1175)","2","pure_quanta","I94";
;
LOCATION"C6590"
$SEC"1"
CDS_SEC"1"
VALUE"DIFF BUS_0.22UF"
TOLERANCE"20%"
PACK_TYPE"C0201"
MATERIAL"X6S"
VOLTAGE"6.3V"
PIN_NAMES_ROTATE"TRUE"
CDS_LMAN_SYM_OUTLINE"-25,50,25,-50"
CDS_LIB"pure_quanta"
PART_NUMBER"SP_CH4221MEE01"
LOCATION"C6590";
"2"
$PN"2"68;
"1"
$PN"1"51;
%"Q_CAP_DIFFBUS"
"2","(-7125,1225)","2","pure_quanta","I95";
;
LOCATION"C6589"
$SEC"1"
CDS_SEC"1"
VALUE"DIFF BUS_0.22UF"
TOLERANCE"20%"
PACK_TYPE"C0201"
MATERIAL"X6S"
VOLTAGE"6.3V"
PIN_NAMES_ROTATE"TRUE"
CDS_LMAN_SYM_OUTLINE"-25,50,25,-50"
CDS_LIB"pure_quanta"
PART_NUMBER"SP_CH4221MEE01"
LOCATION"C6589";
"2"
$PN"2"65;
"1"
$PN"1"52;
%"Q_CAP_DIFFBUS"
"2","(-7125,1375)","2","pure_quanta","I96";
;
LOCATION"C6588"
$SEC"1"
CDS_SEC"1"
VALUE"DIFF BUS_0.22UF"
TOLERANCE"20%"
PACK_TYPE"C0201"
MATERIAL"X6S"
VOLTAGE"6.3V"
PIN_NAMES_ROTATE"TRUE"
CDS_LIB"pure_quanta"
CDS_LMAN_SYM_OUTLINE"-25,50,25,-50"
PART_NUMBER"SP_CH4221MEE01"
LOCATION"C6588";
"2"
$PN"2"67;
"1"
$PN"1"50;
%"Q_CAP_DIFFBUS"
"2","(-7125,1425)","2","pure_quanta","I97";
;
LOCATION"C6587"
$SEC"1"
CDS_SEC"1"
VALUE"DIFF BUS_0.22UF"
TOLERANCE"20%"
PACK_TYPE"C0201"
MATERIAL"X6S"
VOLTAGE"6.3V"
PIN_NAMES_ROTATE"TRUE"
CDS_LIB"pure_quanta"
CDS_LMAN_SYM_OUTLINE"-25,50,25,-50"
PART_NUMBER"SP_CH4221MEE01"
LOCATION"C6587";
"2"
$PN"2"64;
"1"
$PN"1"48;
%"Q_CAP_DIFFBUS"
"2","(-7125,1575)","2","pure_quanta","I98";
;
LOCATION"C6586"
$SEC"1"
CDS_SEC"1"
VALUE"DIFF BUS_0.22UF"
TOLERANCE"20%"
PACK_TYPE"C0201"
MATERIAL"X6S"
VOLTAGE"6.3V"
PIN_NAMES_ROTATE"TRUE"
CDS_LIB"pure_quanta"
CDS_LMAN_SYM_OUTLINE"-25,50,25,-50"
PART_NUMBER"SP_CH4221MEE01"
LOCATION"C6586";
"2"
$PN"2"66;
"1"
$PN"1"49;
%"Q_CAP_DIFFBUS"
"2","(-7125,1625)","2","pure_quanta","I99";
;
LOCATION"C6585"
$SEC"1"
CDS_SEC"1"
VALUE"DIFF BUS_0.22UF"
TOLERANCE"20%"
PACK_TYPE"C0201"
MATERIAL"X6S"
VOLTAGE"6.3V"
PIN_NAMES_ROTATE"TRUE"
CDS_LIB"pure_quanta"
CDS_LMAN_SYM_OUTLINE"-25,50,25,-50"
PART_NUMBER"SP_CH4221MEE01"
LOCATION"C6585";
"2"
$PN"2"61;
"1"
$PN"1"47;
END.
